(kicad_pcb
	(version 20260206)
	(generator "pcbnew")
	(generator_version "10.0")
	(general
		(thickness 1.6)
		(legacy_teardrops no)
	)
	(paper "A4")
	(title_block
		(title "Bryce Canyon_R.DPB_16317-1_OCP.brd")
		(comment 1 "Bryce Canyon / footprints 1415-1417 of 2099")
	)
	(layers
		(0 "F.Cu" signal "TOP")
		(4 "In1.Cu" signal "L2GND")
		(6 "In2.Cu" signal "L3")
		(8 "In3.Cu" signal "L4VCC")
		(10 "In4.Cu" signal "L5VCC")
		(12 "In5.Cu" signal "L6")
		(14 "In6.Cu" signal "L7GND")
		(2 "B.Cu" signal "BOTTOM")
		(9 "F.Adhes" user "F.Adhesive")
		(11 "B.Adhes" user "B.Adhesive")
		(13 "F.Paste" user "Package Geometry/Pastemask Top")
		(15 "B.Paste" user "Package Geometry/Pastemask Bottom")
		(5 "F.SilkS" user "Ref Des/Silkscreen Top")
		(7 "B.SilkS" user "Ref Des/Silkscreen Bottom")
		(1 "F.Mask" user "Board Geometry/Soldermask Top")
		(3 "B.Mask" user "Board Geometry/Soldermask Bottom")
		(17 "Dwgs.User" user "User.Drawings")
		(19 "Cmts.User" user "User.Comments")
		(21 "Eco1.User" user "User.Eco1")
		(23 "Eco2.User" user "User.Eco2")
		(25 "Edge.Cuts" user "Board Geometry/Outline")
		(27 "Margin" user)
		(31 "F.CrtYd" user "Package Geometry/Place Bound Top")
		(29 "B.CrtYd" user "Package Geometry/Place Bound Bottom")
		(35 "F.Fab" user "Ref Des/Assembly Top")
		(33 "B.Fab" user "Ref Des/Assembly Bottom")
	)
	(footprint ""
		(layer "F.Cu")
		(at 245.387622 -215.265 180)
		(property "Reference" "R82"
			(at 0 0 180)
			(layer "F.SilkS")
			(hide yes)
			(effects
				(font
					(size 1.27 1.27)
				)
			)
		)
		(property "Value" "4K7R2F-GP"
			(at 0.064008 -3.993896 180)
			(unlocked yes)
			(layer "F.Fab")
			(hide yes)
			(effects
				(font
					(size 1.016 1.016)
					(thickness 0.1524)
				)
			)
		)
		(property "Device Type" "R402H16"
			(at 0.064008 -5.517896 180)
			(unlocked yes)
			(layer "F.Fab")
			(hide yes)
			(effects
				(font
					(size 1.016 1.016)
					(thickness 0.1524)
				)
			)
		)
		(duplicate_pad_numbers_are_jumpers no)
		(fp_line
			(start 0.508 -0.9398)
			(end -0.508 -0.9398)
			(stroke
				(width 0.1524)
				(type default)
			)
			(layer "F.SilkS")
		)
		(fp_line
			(start -0.508 -0.9398)
			(end -0.508 0.9398)
			(stroke
				(width 0.1524)
				(type default)
			)
			(layer "F.SilkS")
		)
		(fp_rect
			(start -0.508 0.9398)
			(end 0.508 -0.9398)
			(stroke
				(width 0)
				(type default)
			)
			(fill no)
			(layer "F.CrtYd")
		)
		(fp_rect
			(start -0.508 0.9398)
			(end 0.508 -0.9398)
			(stroke
				(width 0)
				(type default)
			)
			(fill no)
			(layer "F.Fab")
		)
		(pad "1" smd custom
			(at 0 -0.4445 180)
			(size 0.1397 0.1397)
			(layers "F.Cu" "F.Mask" "F.Paste")
			(net "P3V3_STBY_B")
			(options
				(clearance outline)
				(anchor circle)
			)
			(primitives
				(gr_poly
					(pts
						(arc
							(start -0.1778 -0.2794)
							(mid -0.249642 -0.249642)
							(end -0.2794 -0.1778)
						)
						(arc
							(start -0.2794 0.1778)
							(mid -0.249642 0.249642)
							(end -0.1778 0.2794)
						)
						(arc
							(start 0.1778 0.2794)
							(mid 0.249642 0.249642)
							(end 0.2794 0.1778)
						)
						(arc
							(start 0.2794 -0.1778)
							(mid 0.249642 -0.249642)
							(end 0.1778 -0.2794)
						)
					)
					(width 0)
					(fill yes)
				)
			)
		)
		(pad "2" smd custom
			(at 0 0.4445 180)
			(size 0.1397 0.1397)
			(layers "F.Cu" "F.Mask" "F.Paste")
			(net "IO_EXP3_A2")
			(options
				(clearance outline)
				(anchor circle)
			)
			(primitives
				(gr_poly
					(pts
						(arc
							(start -0.1778 -0.2794)
							(mid -0.249642 -0.249642)
							(end -0.2794 -0.1778)
						)
						(arc
							(start -0.2794 0.1778)
							(mid -0.249642 0.249642)
							(end -0.1778 0.2794)
						)
						(arc
							(start 0.1778 0.2794)
							(mid 0.249642 0.249642)
							(end 0.2794 0.1778)
						)
						(arc
							(start 0.2794 -0.1778)
							(mid 0.249642 -0.249642)
							(end 0.1778 -0.2794)
						)
					)
					(width 0)
					(fill yes)
				)
			)
		)
	)
	(footprint ""
		(layer "F.Cu")
		(at 228.96449 -353.280726 180)
		(property "Reference" "C517"
			(at 0 0 180)
			(layer "F.SilkS")
			(hide yes)
			(effects
				(font
					(size 1.27 1.27)
				)
			)
		)
		(property "Value" "SC22U25V6KX-2-GP-U"
			(at -2.860802 -5.279644 180)
			(unlocked yes)
			(layer "F.Fab")
			(hide yes)
			(effects
				(font
					(size 1.016 1.016)
					(thickness 0.1524)
				)
			)
		)
		(property "Device Type" "C1206-TO0D3H75"
			(at -2.860802 -6.803644 180)
			(unlocked yes)
			(layer "F.Fab")
			(hide yes)
			(effects
				(font
					(size 1.016 1.016)
					(thickness 0.1524)
				)
			)
		)
		(duplicate_pad_numbers_are_jumpers no)
		(fp_line
			(start 1.3081 2.3749)
			(end -1.3081 2.3749)
			(stroke
				(width 0.1524)
				(type default)
			)
			(layer "F.SilkS")
		)
		(fp_line
			(start 1.3081 -2.3749)
			(end 1.3081 2.3749)
			(stroke
				(width 0.1524)
				(type default)
			)
			(layer "F.SilkS")
		)
		(fp_line
			(start -1.3081 2.3749)
			(end -1.3081 -2.3749)
			(stroke
				(width 0.1524)
				(type default)
			)
			(layer "F.SilkS")
		)
		(fp_line
			(start -1.3081 -2.3749)
			(end 1.3081 -2.3749)
			(stroke
				(width 0.1524)
				(type default)
			)
			(layer "F.SilkS")
		)
		(fp_rect
			(start -0.8001 1.6002)
			(end 0.8001 -1.6002)
			(stroke
				(width 0)
				(type default)
			)
			(fill no)
			(layer "F.CrtYd")
		)
		(fp_poly
			(pts
				(xy -1.5621 2.4511) (xy -1.5621 1.6002) (xy 0.8001 1.6002) (xy 0.8001 -1.6002) (xy -0.8001 -1.6002)
				(xy -0.8001 1.5875) (xy -1.5621 1.5875) (xy -1.5621 -2.4511) (xy 1.5621 -2.4511) (xy 1.5621 2.4511)
			)
			(stroke
				(width 0)
				(type default)
			)
			(fill no)
			(layer "F.CrtYd")
		)
		(fp_rect
			(start -1.5621 2.4511)
			(end 1.5621 -2.4511)
			(stroke
				(width 0)
				(type default)
			)
			(fill no)
			(layer "F.Fab")
		)
		(pad "1" smd rect
			(at 0 -1.392936 180)
			(size 2.1082 1.4478)
			(layers "F.Cu" "F.Mask" "F.Paste")
			(net "P12V_IN")
		)
		(pad "2" smd rect
			(at 0 1.392936 180)
			(size 2.1082 1.4478)
			(layers "F.Cu" "F.Mask" "F.Paste")
			(net "GND")
		)
	)
	(footprint ""
		(layer "F.Cu")
		(at 388.649972 -28.910026 -90)
		(property "Reference" "HDDSAS32"
			(at 0 0 270)
			(layer "F.SilkS")
			(hide yes)
			(effects
				(font
					(size 1.27 1.27)
				)
			)
		)
		(property "Value" "SKT-SAS15P-14P-45-GP"
			(at -20.7645 -8.9789 270)
			(unlocked yes)
			(layer "F.Fab")
			(hide yes)
			(effects
				(font
					(size 1.016 1.016)
					(thickness 0.1524)
				)
			)
		)
		(property "Device Type" "10120818-001C-TRLF"
			(at -20.7645 -10.5029 270)
			(unlocked yes)
			(layer "F.Fab")
			(hide yes)
			(effects
				(font
					(size 1.016 1.016)
					(thickness 0.1524)
				)
			)
		)
		(duplicate_pad_numbers_are_jumpers no)
		(fp_line
			(start 1.651 4.2926)
			(end 1.651 3.0099)
			(stroke
				(width 0.1524)
				(type default)
			)
			(layer "F.SilkS")
		)
		(fp_line
			(start 8.509 4.2926)
			(end 1.651 4.2926)
			(stroke
				(width 0.1524)
				(type default)
			)
			(layer "F.SilkS")
		)
		(fp_line
			(start -23.4188 3.0099)
			(end -23.4188 -3.2512)
			(stroke
				(width 0.1524)
				(type default)
			)
			(layer "F.SilkS")
		)
		(fp_line
			(start 1.651 3.0099)
			(end -23.4188 3.0099)
			(stroke
				(width 0.1524)
				(type default)
			)
			(layer "F.SilkS")
		)
		(fp_line
			(start 8.509 3.0099)
			(end 8.509 4.2926)
			(stroke
				(width 0.1524)
				(type default)
			)
			(layer "F.SilkS")
		)
		(fp_line
			(start 23.4188 3.0099)
			(end 8.509 3.0099)
			(stroke
				(width 0.1524)
				(type default)
			)
			(layer "F.SilkS")
		)
		(fp_line
			(start -23.4188 -3.2512)
			(end 23.4188 -3.2512)
			(stroke
				(width 0.1524)
				(type default)
			)
			(layer "F.SilkS")
		)
		(fp_line
			(start 23.4188 -3.2512)
			(end 23.4188 3.0099)
			(stroke
				(width 0.1524)
				(type default)
			)
			(layer "F.SilkS")
		)
		(fp_line
			(start 15.5067 -3.3401)
			(end 16.2687 -3.3401)
			(stroke
				(width 0.3302)
				(type default)
			)
			(layer "F.SilkS")
		)
		(fp_poly
			(pts
				(xy 15.868904 -3.230372) (xy 16.503904 -3.865372) (xy 15.233904 -3.865372)
			)
			(stroke
				(width 0)
				(type default)
			)
			(fill yes)
			(layer "F.SilkS")
		)
		(fp_poly
			(pts
				(xy -22.8727 -2.7559) (xy 22.8727 -2.7559) (xy 22.8727 2.7559) (xy 8.255 2.7559) (xy 8.255 3.5179)
				(xy 1.905 3.5179) (xy 1.905 2.7559) (xy -22.8727 2.7559)
			)
			(stroke
				(width 0)
				(type default)
			)
			(fill no)
			(layer "F.CrtYd")
		)
		(fp_poly
			(pts
				(xy 1.397 4.5466) (xy 1.397 3.2639) (xy -23.6728 3.2639) (xy -23.6728 -3.5052) (xy 23.6728 -3.5052)
				(xy 23.6728 -0.00635) (xy 22.8727 -0.00635) (xy 22.8727 -2.7559) (xy -22.8727 -2.7559) (xy -22.8727 2.7559)
				(xy 1.905 2.7559) (xy 1.905 3.5179) (xy 8.255 3.5179) (xy 8.255 2.7559) (xy 22.8727 2.7559) (xy 22.8727 0.00635)
				(xy 23.6728 0.00635) (xy 23.6728 3.2639) (xy 8.763 3.2639) (xy 8.763 4.5466)
			)
			(stroke
				(width 0)
				(type default)
			)
			(fill no)
			(layer "F.CrtYd")
		)
		(fp_poly
			(pts
				(xy 1.397 4.5466) (xy 1.397 3.2639) (xy -23.6728 3.2639) (xy -23.6728 -3.5052) (xy 23.6728 -3.5052)
				(xy 23.6728 3.2639) (xy 8.763 3.2639) (xy 8.763 4.5466)
			)
			(stroke
				(width 0)
				(type default)
			)
			(fill no)
			(layer "F.Fab")
		)
		(pad "" np_thru_hole circle
			(at -18.874994 0 270)
			(size 0.254 0.254)
			(drill 1.3462)
			(layers "*.Cu" "*.Mask")
			(clearance 0.9017)
			(thermal_gap 0.9017)
		)
		(pad "" np_thru_hole circle
			(at 18.874994 0 270)
			(size 0.254 0.254)
			(drill 0.9398)
			(layers "*.Cu" "*.Mask")
			(clearance 0.6985)
			(thermal_gap 0.6985)
		)
		(pad "G1" smd rect
			(at 21.874988 0 270)
			(size 2.5908 2.5908)
			(layers "F.Cu" "F.Mask" "F.Paste")
			(net "GND")
		)
		(pad "G2" smd rect
			(at -21.874988 0 270)
			(size 2.5908 2.5908)
			(layers "F.Cu" "F.Mask" "F.Paste")
			(net "GND")
		)
		(pad "P1" smd rect
			(at 1.905 -1.82499 270)
			(size 0.6096 2.3622)
			(layers "F.Cu" "F.Mask" "F.Paste")
			(net "Net_1634")
		)
		(pad "P2" smd rect
			(at 0.635 -1.82499 270)
			(size 0.6096 2.3622)
			(layers "F.Cu" "F.Mask" "F.Paste")
			(net "Net_1635")
		)
		(pad "P3" smd rect
			(at -0.635 -1.82499 270)
			(size 0.6096 2.3622)
			(layers "F.Cu" "F.Mask" "F.Paste")
			(net "Net_1636")
		)
		(pad "P4" smd rect
			(at -1.905 -1.82499 270)
			(size 0.6096 2.3622)
			(layers "F.Cu" "F.Mask" "F.Paste")
			(net "GND")
		)
		(pad "P5" smd rect
			(at -3.175 -1.82499 270)
			(size 0.6096 2.3622)
			(layers "F.Cu" "F.Mask" "F.Paste")
			(net "HDD_PRSNT_32")
		)
		(pad "P6" smd rect
			(at -4.445 -1.82499 270)
			(size 0.6096 2.3622)
			(layers "F.Cu" "F.Mask" "F.Paste")
			(net "GND")
		)
		(pad "P7" smd rect
			(at -5.715 -1.82499 270)
			(size 0.6096 2.3622)
			(layers "F.Cu" "F.Mask" "F.Paste")
			(net "5V_PRE_32")
		)
		(pad "P8" smd rect
			(at -6.985 -1.82499 270)
			(size 0.6096 2.3622)
			(layers "F.Cu" "F.Mask" "F.Paste")
			(net "P5V_HDD32")
		)
		(pad "P9" smd rect
			(at -8.255 -1.82499 270)
			(size 0.6096 2.3622)
			(layers "F.Cu" "F.Mask" "F.Paste")
			(net "P5V_HDD32")
		)
		(pad "P10" smd rect
			(at -9.525 -1.82499 270)
			(size 0.6096 2.3622)
			(layers "F.Cu" "F.Mask" "F.Paste")
			(net "GND")
		)
		(pad "P11" smd rect
			(at -10.795 -1.82499 270)
			(size 0.6096 2.3622)
			(layers "F.Cu" "F.Mask" "F.Paste")
			(net "ACT_HDD_32")
		)
		(pad "P12" smd rect
			(at -12.065 -1.82499 270)
			(size 0.6096 2.3622)
			(layers "F.Cu" "F.Mask" "F.Paste")
			(net "GND")
		)
		(pad "P13" smd rect
			(at -13.335 -1.82499 270)
			(size 0.6096 2.3622)
			(layers "F.Cu" "F.Mask" "F.Paste")
			(net "12V_PRE_32")
		)
		(pad "P14" smd rect
			(at -14.605 -1.82499 270)
			(size 0.6096 2.3622)
			(layers "F.Cu" "F.Mask" "F.Paste")
			(net "P12V_HDD32")
		)
		(pad "P15" smd rect
			(at -15.875 -1.82499 270)
			(size 0.6096 2.3622)
			(layers "F.Cu" "F.Mask" "F.Paste")
			(net "P12V_HDD32")
		)
		(pad "S1" smd rect
			(at 15.875 -1.82499 270)
			(size 0.6096 2.3622)
			(layers "F.Cu" "F.Mask" "F.Paste")
			(net "GND")
		)
		(pad "S2" smd rect
			(at 14.605 -1.82499 270)
			(size 0.6096 2.3622)
			(layers "F.Cu" "F.Mask" "F.Paste")
			(net "SAS_HDD_RX_P32")
		)
		(pad "S3" smd rect
			(at 13.335 -1.82499 270)
			(size 0.6096 2.3622)
			(layers "F.Cu" "F.Mask" "F.Paste")
			(net "SAS_HDD_RX_N32")
		)
		(pad "S4" smd rect
			(at 12.065 -1.82499 270)
			(size 0.6096 2.3622)
			(layers "F.Cu" "F.Mask" "F.Paste")
			(net "GND")
		)
		(pad "S5" smd rect
			(at 10.795 -1.82499 270)
			(size 0.6096 2.3622)
			(layers "F.Cu" "F.Mask" "F.Paste")
			(net "PHY_DRV_B_TO_SCC_B_32_DN")
		)
		(pad "S6" smd rect
			(at 9.525 -1.82499 270)
			(size 0.6096 2.3622)
			(layers "F.Cu" "F.Mask" "F.Paste")
			(net "PHY_DRV_B_TO_SCC_B_32_DP")
		)
		(pad "S7" smd rect
			(at 8.255 -1.82499 270)
			(size 0.6096 2.3622)
			(layers "F.Cu" "F.Mask" "F.Paste")
			(net "GND")
		)
		(pad "S8" smd rect
			(at 7.480046 2.845054 270)
			(size 0.508 2.3622)
			(layers "F.Cu" "F.Mask" "F.Paste")
			(net "GND")
		)
		(pad "S9" smd rect
			(at 6.679946 2.845054 270)
			(size 0.508 2.3622)
			(layers "F.Cu" "F.Mask" "F.Paste")
			(net "Net_457")
		)
		(pad "S10" smd rect
			(at 5.8801 2.845054 270)
			(size 0.508 2.3622)
			(layers "F.Cu" "F.Mask" "F.Paste")
			(net "Net_349")
		)
		(pad "S11" smd rect
			(at 5.08 2.845054 270)
			(size 0.508 2.3622)
			(layers "F.Cu" "F.Mask" "F.Paste")
			(net "GND")
		)
		(pad "S12" smd rect
			(at 4.2799 2.845054 270)
			(size 0.508 2.3622)
			(layers "F.Cu" "F.Mask" "F.Paste")
			(net "Net_385")
		)
		(pad "S13" smd rect
			(at 3.480054 2.845054 270)
			(size 0.508 2.3622)
			(layers "F.Cu" "F.Mask" "F.Paste")
			(net "Net_421")
		)
		(pad "S14" smd rect
			(at 2.679954 2.845054 270)
			(size 0.508 2.3622)
			(layers "F.Cu" "F.Mask" "F.Paste")
			(net "GND")
		)
		(zone
			(layer "F.Cu")
			(hatch none 0.5)
			(connect_pads
				(clearance 0)
			)
			(min_thickness 0.25)
			(keepout
				(tracks not_allowed)
				(vias allowed)
				(pads allowed)
				(copperpour not_allowed)
				(footprints allowed)
			)
			(placement
				(enabled no)
				(sheetname "")
			)
			(fill
				(thermal_gap 0.5)
				(thermal_bridge_width 0.5)
				(island_removal_mode 0)
			)
			(polygon
				(pts
					(xy 392.307572 -45.648626) (xy 385.233672 -45.648626) (xy 385.233672 -52.582826) (xy 386.338572 -52.582826)
					(xy 386.338572 -48.468026) (xy 390.961372 -48.468026) (xy 390.961372 -52.582826) (xy 392.307572 -52.582826)
				)
			)
		)
		(zone
			(layer "F.Cu")
			(hatch none 0.5)
			(connect_pads
				(clearance 0)
			)
			(min_thickness 0.25)
			(keepout
				(tracks allowed)
				(vias not_allowed)
				(pads allowed)
				(copperpour not_allowed)
				(footprints allowed)
			)
			(placement
				(enabled no)
				(sheetname "")
			)
			(fill
				(thermal_gap 0.5)
				(thermal_bridge_width 0.5)
				(island_removal_mode 0)
			)
			(polygon
				(pts
					(xy 392.307572 -45.648626) (xy 385.233672 -45.648626) (xy 385.233672 -52.582826) (xy 386.338572 -52.582826)
					(xy 386.338572 -48.468026) (xy 390.961372 -48.468026) (xy 390.961372 -52.582826) (xy 392.307572 -52.582826)
				)
			)
		)
		(zone
			(layer "F.Cu")
			(hatch none 0.5)
			(connect_pads
				(clearance 0)
			)
			(min_thickness 0.25)
			(keepout
				(tracks not_allowed)
				(vias allowed)
				(pads allowed)
				(copperpour not_allowed)
				(footprints allowed)
			)
			(placement
				(enabled no)
				(sheetname "")
			)
			(fill
				(thermal_gap 0.5)
				(thermal_bridge_width 0.5)
				(island_removal_mode 0)
			)
			(polygon
				(pts
					(xy 392.307572 -12.171426) (xy 385.233672 -12.171426) (xy 385.233672 -5.237226) (xy 386.338572 -5.237226)
					(xy 386.338572 -9.352026) (xy 390.961372 -9.352026) (xy 390.961372 -5.237226) (xy 392.307572 -5.237226)
				)
			)
		)
		(zone
			(layer "F.Cu")
			(hatch none 0.5)
			(connect_pads
				(clearance 0)
			)
			(min_thickness 0.25)
			(keepout
				(tracks allowed)
				(vias not_allowed)
				(pads allowed)
				(copperpour not_allowed)
				(footprints allowed)
			)
			(placement
				(enabled no)
				(sheetname "")
			)
			(fill
				(thermal_gap 0.5)
				(thermal_bridge_width 0.5)
				(island_removal_mode 0)
			)
			(polygon
				(pts
					(xy 392.307572 -12.171426) (xy 385.233672 -12.171426) (xy 385.233672 -5.237226) (xy 386.338572 -5.237226)
					(xy 386.338572 -9.352026) (xy 390.961372 -9.352026) (xy 390.961372 -5.237226) (xy 392.307572 -5.237226)
				)
			)
		)
		(zone
			(layers "F.Cu" "B.Cu" "In1.Cu" "In2.Cu" "In3.Cu" "In4.Cu" "In5.Cu" "In6.Cu")
			(hatch none 0.5)
			(connect_pads
				(clearance 0)
			)
			(min_thickness 0.25)
			(keepout
				(tracks not_allowed)
				(vias allowed)
				(pads allowed)
				(copperpour not_allowed)
				(footprints allowed)
			)
			(placement
				(enabled no)
				(sheetname "")
			)
			(fill
				(thermal_gap 0.5)
				(thermal_bridge_width 0.5)
				(island_removal_mode 0)
			)
			(polygon
				(pts
					(arc
						(start 389.424672 -10.035032)
						(mid 387.875272 -10.035032)
						(end 389.424672 -10.035032)
					)
				)
			)
		)
		(zone
			(layers "F.Cu" "B.Cu" "In1.Cu" "In2.Cu" "In3.Cu" "In4.Cu" "In5.Cu" "In6.Cu")
			(hatch none 0.5)
			(connect_pads
				(clearance 0)
			)
			(min_thickness 0.25)
			(keepout
				(tracks not_allowed)
				(vias allowed)
				(pads allowed)
				(copperpour not_allowed)
				(footprints allowed)
			)
			(placement
				(enabled no)
				(sheetname "")
			)
			(fill
				(thermal_gap 0.5)
				(thermal_bridge_width 0.5)
				(island_removal_mode 0)
			)
			(polygon
				(pts
					(arc
						(start 389.627872 -47.78502)
						(mid 387.672072 -47.78502)
						(end 389.627872 -47.78502)
					)
				)
			)
		)
	)
)
